(kicad_pcb
	(version 20260206)
	(generator "pcbnew")
	(generator_version "10.0")
	(general
		(thickness 1.6)
		(legacy_teardrops no)
	)
	(paper "A4")
	(title_block
		(title "01162023_DA0F0TEBIF0_F0T_Expander_BD_F_brd_V02_OCP.brd")
		(comment 1 "Grand Teton / footprints 6741-6747 of 9728")
	)
	(layers
		(0 "F.Cu" signal "TOP")
		(4 "In1.Cu" signal "GND")
		(6 "In2.Cu" signal "VCC")
		(8 "In3.Cu" signal "VCC1")
		(10 "In4.Cu" signal "GND1")
		(12 "In5.Cu" signal "IN1")
		(14 "In6.Cu" signal "GND2")
		(16 "In7.Cu" signal "IN2")
		(18 "In8.Cu" signal "GND3")
		(20 "In9.Cu" signal "IN3")
		(22 "In10.Cu" signal "GND4")
		(24 "In11.Cu" signal "IN4")
		(26 "In12.Cu" signal "GND5")
		(28 "In13.Cu" signal "IN5")
		(30 "In14.Cu" signal "GND6")
		(32 "In15.Cu" signal "IN6")
		(34 "In16.Cu" signal "GND7")
		(2 "B.Cu" signal "BOTTOM")
		(9 "F.Adhes" user "F.Adhesive")
		(11 "B.Adhes" user "B.Adhesive")
		(13 "F.Paste" user "Package Geometry/Pastemask Top")
		(15 "B.Paste" user "Package Geometry/Pastemask Bottom")
		(5 "F.SilkS" user "Ref Des/Silkscreen Top")
		(7 "B.SilkS" user "Ref Des/Silkscreen Bottom")
		(1 "F.Mask" user "Board Geometry/Soldermask Top")
		(3 "B.Mask" user "Board Geometry/Soldermask Bottom")
		(17 "Dwgs.User" user "User.Drawings")
		(19 "Cmts.User" user "User.Comments")
		(21 "Eco1.User" user "User.Eco1")
		(23 "Eco2.User" user "User.Eco2")
		(25 "Edge.Cuts" user "Board Geometry/Outline")
		(27 "Margin" user)
		(31 "F.CrtYd" user "Package Geometry/Place Bound Top")
		(29 "B.CrtYd" user "Package Geometry/Place Bound Bottom")
		(35 "F.Fab" user "Ref Des/Assembly Top")
		(33 "B.Fab" user "Ref Des/Assembly Bottom")
	)
	(footprint ""
		(layer "F.Cu")
		(at 310.467756 -54.067456)
		(property "Reference" "PR233"
			(at 0 0 0)
			(layer "F.SilkS")
			(hide yes)
			(effects
				(font
					(size 1.27 1.27)
				)
			)
		)
		(property "Value" ""
			(at 0 0 0)
			(layer "F.Fab")
			(effects
				(font
					(size 1.27 1.27)
				)
			)
		)
		(duplicate_pad_numbers_are_jumpers no)
		(fp_line
			(start -0.7874 -0.4064)
			(end 0.7874 -0.4064)
			(stroke
				(width 0.1524)
				(type default)
			)
			(layer "F.SilkS")
		)
		(fp_line
			(start -0.7874 0.4064)
			(end -0.7874 -0.4064)
			(stroke
				(width 0.1524)
				(type default)
			)
			(layer "F.SilkS")
		)
		(fp_line
			(start 0.7874 -0.4064)
			(end 0.7874 0.4064)
			(stroke
				(width 0.1524)
				(type default)
			)
			(layer "F.SilkS")
		)
		(fp_line
			(start 0.7874 0.4064)
			(end -0.7874 0.4064)
			(stroke
				(width 0.1524)
				(type default)
			)
			(layer "F.SilkS")
		)
		(fp_line
			(start -0.67945 -0.305054)
			(end -0.12065 -0.305054)
			(stroke
				(width 0.1)
				(type default)
			)
			(layer "F.Fab")
		)
		(fp_line
			(start -0.67945 0.3048)
			(end -0.67945 -0.305054)
			(stroke
				(width 0.1)
				(type default)
			)
			(layer "F.Fab")
		)
		(fp_line
			(start -0.12065 -0.305054)
			(end -0.12065 -0.2794)
			(stroke
				(width 0.1)
				(type default)
			)
			(layer "F.Fab")
		)
		(fp_line
			(start -0.12065 -0.2794)
			(end 0.12065 -0.2794)
			(stroke
				(width 0.1)
				(type default)
			)
			(layer "F.Fab")
		)
		(fp_line
			(start -0.12065 0.2794)
			(end -0.12065 0.3048)
			(stroke
				(width 0.1)
				(type default)
			)
			(layer "F.Fab")
		)
		(fp_line
			(start -0.12065 0.3048)
			(end -0.67945 0.3048)
			(stroke
				(width 0.1)
				(type default)
			)
			(layer "F.Fab")
		)
		(fp_line
			(start 0.120396 0.2794)
			(end -0.12065 0.2794)
			(stroke
				(width 0.1)
				(type default)
			)
			(layer "F.Fab")
		)
		(fp_line
			(start 0.120396 0.3048)
			(end 0.120396 0.2794)
			(stroke
				(width 0.1)
				(type default)
			)
			(layer "F.Fab")
		)
		(fp_line
			(start 0.12065 -0.3048)
			(end 0.67945 -0.3048)
			(stroke
				(width 0.1)
				(type default)
			)
			(layer "F.Fab")
		)
		(fp_line
			(start 0.12065 -0.2794)
			(end 0.12065 -0.3048)
			(stroke
				(width 0.1)
				(type default)
			)
			(layer "F.Fab")
		)
		(fp_line
			(start 0.67945 -0.3048)
			(end 0.67945 0.3048)
			(stroke
				(width 0.1)
				(type default)
			)
			(layer "F.Fab")
		)
		(fp_line
			(start 0.67945 0.3048)
			(end 0.120396 0.3048)
			(stroke
				(width 0.1)
				(type default)
			)
			(layer "F.Fab")
		)
		(pad "1" smd circle
			(at -0.40005 0)
			(size 0 0)
			(layers "F.Cu" "F.Mask" "F.Paste")
			(net "P12V_SSD10_OCP")
		)
		(pad "2" smd circle
			(at 0.40005 0)
			(size 0 0)
			(layers "F.Cu" "F.Mask" "F.Paste")
			(net "GND")
		)
	)
	(footprint ""
		(layer "F.Cu")
		(at 452.051674 -208.948782 90)
		(property "Reference" "U108"
			(at -2.813558 -1.527302 0)
			(unlocked yes)
			(layer "F.SilkS")
			(effects
				(font
					(size 0.7874 0.5842)
					(thickness 0.1524)
				)
				(justify left)
			)
		)
		(property "Value" ""
			(at 0 0 90)
			(layer "F.Fab")
			(effects
				(font
					(size 1.27 1.27)
				)
			)
		)
		(duplicate_pad_numbers_are_jumpers no)
		(fp_poly
			(pts
				(xy -1.5113 -0.750062) (xy -2.1463 -1.067562) (xy -2.1463 -0.432562)
			)
			(stroke
				(width 0)
				(type default)
			)
			(fill yes)
			(layer "F.SilkS")
		)
		(fp_line
			(start 0.700024 -1.500124)
			(end 0.700024 1.500124)
			(stroke
				(width 0.1)
				(type default)
			)
			(layer "F.Fab")
		)
		(fp_line
			(start -0.700024 -1.500124)
			(end 0.700024 -1.500124)
			(stroke
				(width 0.1)
				(type default)
			)
			(layer "F.Fab")
		)
		(fp_line
			(start 0.700024 1.500124)
			(end -0.700024 1.500124)
			(stroke
				(width 0.1)
				(type default)
			)
			(layer "F.Fab")
		)
		(fp_line
			(start -0.700024 1.500124)
			(end -0.700024 -1.500124)
			(stroke
				(width 0.1)
				(type default)
			)
			(layer "F.Fab")
		)
		(fp_poly
			(pts
				(xy -1.5113 -0.750062) (xy -2.1463 -1.067562) (xy -2.1463 -0.432562)
			)
			(stroke
				(width 0)
				(type default)
			)
			(fill yes)
			(layer "F.Fab")
		)
		(pad "1" smd rect
			(at -0.999998 -0.750062 90)
			(size 0.7112 1.016)
			(layers "F.Cu" "F.Mask" "F.Paste")
			(net "GND")
		)
		(pad "2" smd rect
			(at -0.999998 0.94996)
			(size 0.6096 0.7112)
			(layers "F.Cu" "F.Mask" "F.Paste")
			(net "USB2_FT4232_MUX_D_DN")
		)
		(pad "3" smd rect
			(at 0.999998 0.94996)
			(size 0.6096 0.7112)
			(layers "F.Cu" "F.Mask" "F.Paste")
			(net "USB2_FT4232_MUX_D_DP")
		)
		(pad "4" smd rect
			(at 0.999998 -0.94996)
			(size 0.6096 0.7112)
			(layers "F.Cu" "F.Mask" "F.Paste")
			(net "USB_VBUS_CONN")
		)
	)
	(footprint ""
		(layer "F.Cu")
		(at 367.54689 -38.49116 180)
		(property "Reference" "R6113"
			(at 0 0 180)
			(layer "F.SilkS")
			(hide yes)
			(effects
				(font
					(size 1.27 1.27)
				)
			)
		)
		(property "Value" ""
			(at 0 0 180)
			(layer "F.Fab")
			(effects
				(font
					(size 1.27 1.27)
				)
			)
		)
		(duplicate_pad_numbers_are_jumpers no)
		(fp_line
			(start 0.7874 0.4064)
			(end -0.7874 0.4064)
			(stroke
				(width 0.1524)
				(type default)
			)
			(layer "F.SilkS")
		)
		(fp_line
			(start 0.7874 -0.4064)
			(end 0.7874 0.4064)
			(stroke
				(width 0.1524)
				(type default)
			)
			(layer "F.SilkS")
		)
		(fp_line
			(start -0.7874 0.4064)
			(end -0.7874 -0.4064)
			(stroke
				(width 0.1524)
				(type default)
			)
			(layer "F.SilkS")
		)
		(fp_line
			(start -0.7874 -0.4064)
			(end 0.7874 -0.4064)
			(stroke
				(width 0.1524)
				(type default)
			)
			(layer "F.SilkS")
		)
		(fp_line
			(start 0.67945 0.3048)
			(end 0.120396 0.3048)
			(stroke
				(width 0.1)
				(type default)
			)
			(layer "F.Fab")
		)
		(fp_line
			(start 0.67945 -0.3048)
			(end 0.67945 0.3048)
			(stroke
				(width 0.1)
				(type default)
			)
			(layer "F.Fab")
		)
		(fp_line
			(start 0.12065 -0.2794)
			(end 0.12065 -0.3048)
			(stroke
				(width 0.1)
				(type default)
			)
			(layer "F.Fab")
		)
		(fp_line
			(start 0.12065 -0.3048)
			(end 0.67945 -0.3048)
			(stroke
				(width 0.1)
				(type default)
			)
			(layer "F.Fab")
		)
		(fp_line
			(start 0.120396 0.3048)
			(end 0.120396 0.2794)
			(stroke
				(width 0.1)
				(type default)
			)
			(layer "F.Fab")
		)
		(fp_line
			(start 0.120396 0.2794)
			(end -0.12065 0.2794)
			(stroke
				(width 0.1)
				(type default)
			)
			(layer "F.Fab")
		)
		(fp_line
			(start -0.12065 0.3048)
			(end -0.67945 0.3048)
			(stroke
				(width 0.1)
				(type default)
			)
			(layer "F.Fab")
		)
		(fp_line
			(start -0.12065 0.2794)
			(end -0.12065 0.3048)
			(stroke
				(width 0.1)
				(type default)
			)
			(layer "F.Fab")
		)
		(fp_line
			(start -0.12065 -0.2794)
			(end 0.12065 -0.2794)
			(stroke
				(width 0.1)
				(type default)
			)
			(layer "F.Fab")
		)
		(fp_line
			(start -0.12065 -0.305054)
			(end -0.12065 -0.2794)
			(stroke
				(width 0.1)
				(type default)
			)
			(layer "F.Fab")
		)
		(fp_line
			(start -0.67945 0.3048)
			(end -0.67945 -0.305054)
			(stroke
				(width 0.1)
				(type default)
			)
			(layer "F.Fab")
		)
		(fp_line
			(start -0.67945 -0.305054)
			(end -0.12065 -0.305054)
			(stroke
				(width 0.1)
				(type default)
			)
			(layer "F.Fab")
		)
		(pad "1" smd circle
			(at -0.40005 0 180)
			(size 0 0)
			(layers "F.Cu" "F.Mask" "F.Paste")
			(net "P3V3_SSD13_PG_G1")
		)
		(pad "2" smd circle
			(at 0.40005 0 180)
			(size 0 0)
			(layers "F.Cu" "F.Mask" "F.Paste")
			(net "GND")
		)
	)
	(footprint ""
		(layer "F.Cu")
		(at 460.027782 -254.344932 -90)
		(property "Reference" "C4399"
			(at 0 0 270)
			(layer "F.SilkS")
			(hide yes)
			(effects
				(font
					(size 1.27 1.27)
				)
			)
		)
		(property "Value" ""
			(at 0 0 270)
			(layer "F.Fab")
			(effects
				(font
					(size 1.27 1.27)
				)
			)
		)
		(duplicate_pad_numbers_are_jumpers no)
		(fp_line
			(start -1.524 0.762)
			(end -1.524 -0.762)
			(stroke
				(width 0.1524)
				(type default)
			)
			(layer "F.SilkS")
		)
		(fp_line
			(start 1.524 0.762)
			(end -1.524 0.762)
			(stroke
				(width 0.1524)
				(type default)
			)
			(layer "F.SilkS")
		)
		(fp_line
			(start -1.524 -0.762)
			(end 1.524 -0.762)
			(stroke
				(width 0.1524)
				(type default)
			)
			(layer "F.SilkS")
		)
		(fp_line
			(start 1.524 -0.762)
			(end 1.524 0.762)
			(stroke
				(width 0.1524)
				(type default)
			)
			(layer "F.SilkS")
		)
		(fp_line
			(start -1.1049 0.724916)
			(end 1.1049 0.724916)
			(stroke
				(width 0.1)
				(type default)
			)
			(layer "F.Fab")
		)
		(fp_line
			(start 1.1049 0.724916)
			(end 1.1049 -0.724916)
			(stroke
				(width 0.1)
				(type default)
			)
			(layer "F.Fab")
		)
		(fp_line
			(start -1.1049 -0.724916)
			(end -1.1049 0.724916)
			(stroke
				(width 0.1)
				(type default)
			)
			(layer "F.Fab")
		)
		(fp_line
			(start 1.1049 -0.724916)
			(end -1.1049 -0.724916)
			(stroke
				(width 0.1)
				(type default)
			)
			(layer "F.Fab")
		)
		(pad "1" smd rect
			(at -0.889 0 90)
			(size 1.016 1.27)
			(layers "F.Cu" "F.Mask" "F.Paste")
			(net "P1V25_SERDES_VDDPLL_PEX3_C5")
		)
		(pad "2" smd rect
			(at 0.889 0 90)
			(size 1.016 1.27)
			(layers "F.Cu" "F.Mask" "F.Paste")
			(net "GND")
		)
		(zone
			(layer "F.Cu")
			(hatch none 0.5)
			(connect_pads
				(clearance 0)
			)
			(min_thickness 0.25)
			(keepout
				(tracks not_allowed)
				(vias allowed)
				(pads allowed)
				(copperpour not_allowed)
				(footprints allowed)
			)
			(placement
				(enabled no)
				(sheetname "")
			)
			(fill
				(thermal_gap 0.5)
				(thermal_bridge_width 0.5)
				(island_removal_mode 0)
			)
			(polygon
				(pts
					(xy 460.752698 -254.675132) (xy 459.302866 -254.675132) (xy 459.302866 -254.014732) (xy 460.752698 -254.014732)
				)
			)
		)
	)
	(footprint ""
		(layer "F.Cu")
		(at 115.720368 -320.820034 90)
		(property "Reference" "C4216"
			(at 0 0 90)
			(layer "F.SilkS")
			(hide yes)
			(effects
				(font
					(size 1.27 1.27)
				)
			)
		)
		(property "Value" ""
			(at 0 0 90)
			(layer "F.Fab")
			(effects
				(font
					(size 1.27 1.27)
				)
			)
		)
		(duplicate_pad_numbers_are_jumpers no)
		(fp_line
			(start 1.2954 -0.5842)
			(end 1.2954 0.5842)
			(stroke
				(width 0.1524)
				(type default)
			)
			(layer "F.SilkS")
		)
		(fp_line
			(start -1.2954 -0.5842)
			(end 1.2954 -0.5842)
			(stroke
				(width 0.1524)
				(type default)
			)
			(layer "F.SilkS")
		)
		(fp_line
			(start 1.2954 0.5842)
			(end -1.2954 0.5842)
			(stroke
				(width 0.1524)
				(type default)
			)
			(layer "F.SilkS")
		)
		(fp_line
			(start -1.2954 0.5842)
			(end -1.2954 -0.5842)
			(stroke
				(width 0.1524)
				(type default)
			)
			(layer "F.SilkS")
		)
		(fp_line
			(start 0.8636 -0.4572)
			(end 0.8636 -0.4064)
			(stroke
				(width 0.1)
				(type default)
			)
			(layer "F.Fab")
		)
		(fp_line
			(start -0.8636 -0.4572)
			(end 0.8636 -0.4572)
			(stroke
				(width 0.1)
				(type default)
			)
			(layer "F.Fab")
		)
		(fp_line
			(start 1.1938 -0.4064)
			(end 1.1938 0.4064)
			(stroke
				(width 0.1)
				(type default)
			)
			(layer "F.Fab")
		)
		(fp_line
			(start 0.8636 -0.4064)
			(end 1.1938 -0.4064)
			(stroke
				(width 0.1)
				(type default)
			)
			(layer "F.Fab")
		)
		(fp_line
			(start -0.8636 -0.4064)
			(end -0.8636 -0.4572)
			(stroke
				(width 0.1)
				(type default)
			)
			(layer "F.Fab")
		)
		(fp_line
			(start -1.1938 -0.4064)
			(end -0.8636 -0.4064)
			(stroke
				(width 0.1)
				(type default)
			)
			(layer "F.Fab")
		)
		(fp_line
			(start 1.1938 0.4064)
			(end 0.8636 0.4064)
			(stroke
				(width 0.1)
				(type default)
			)
			(layer "F.Fab")
		)
		(fp_line
			(start 0.8636 0.4064)
			(end 0.8636 0.4572)
			(stroke
				(width 0.1)
				(type default)
			)
			(layer "F.Fab")
		)
		(fp_line
			(start -0.8636 0.4064)
			(end -1.1938 0.4064)
			(stroke
				(width 0.1)
				(type default)
			)
			(layer "F.Fab")
		)
		(fp_line
			(start -1.1938 0.4064)
			(end -1.1938 -0.4064)
			(stroke
				(width 0.1)
				(type default)
			)
			(layer "F.Fab")
		)
		(fp_line
			(start 0.8636 0.4572)
			(end -0.8636 0.4572)
			(stroke
				(width 0.1)
				(type default)
			)
			(layer "F.Fab")
		)
		(fp_line
			(start -0.8636 0.4572)
			(end -0.8636 0.4064)
			(stroke
				(width 0.1)
				(type default)
			)
			(layer "F.Fab")
		)
		(pad "1" smd rect
			(at -0.7366 0)
			(size 0.7112 0.8128)
			(layers "F.Cu" "F.Mask" "F.Paste")
			(net "P0V8_SERDES_VDDA_PEX0_C10")
		)
		(pad "2" smd rect
			(at 0.7366 0)
			(size 0.7112 0.8128)
			(layers "F.Cu" "F.Mask" "F.Paste")
			(net "GND")
		)
	)
	(footprint ""
		(layer "F.Cu")
		(at 86.210902 -61.386974)
		(property "Reference" "R4495"
			(at 0 0 0)
			(layer "F.SilkS")
			(hide yes)
			(effects
				(font
					(size 1.27 1.27)
				)
			)
		)
		(property "Value" ""
			(at 0 0 0)
			(layer "F.Fab")
			(effects
				(font
					(size 1.27 1.27)
				)
			)
		)
		(duplicate_pad_numbers_are_jumpers no)
		(fp_line
			(start -0.7874 -0.4064)
			(end 0.7874 -0.4064)
			(stroke
				(width 0.1524)
				(type default)
			)
			(layer "F.SilkS")
		)
		(fp_line
			(start -0.7874 0.4064)
			(end -0.7874 -0.4064)
			(stroke
				(width 0.1524)
				(type default)
			)
			(layer "F.SilkS")
		)
		(fp_line
			(start 0.7874 -0.4064)
			(end 0.7874 0.4064)
			(stroke
				(width 0.1524)
				(type default)
			)
			(layer "F.SilkS")
		)
		(fp_line
			(start 0.7874 0.4064)
			(end -0.7874 0.4064)
			(stroke
				(width 0.1524)
				(type default)
			)
			(layer "F.SilkS")
		)
		(fp_line
			(start -0.67945 -0.305054)
			(end -0.12065 -0.305054)
			(stroke
				(width 0.1)
				(type default)
			)
			(layer "F.Fab")
		)
		(fp_line
			(start -0.67945 0.3048)
			(end -0.67945 -0.305054)
			(stroke
				(width 0.1)
				(type default)
			)
			(layer "F.Fab")
		)
		(fp_line
			(start -0.12065 -0.305054)
			(end -0.12065 -0.2794)
			(stroke
				(width 0.1)
				(type default)
			)
			(layer "F.Fab")
		)
		(fp_line
			(start -0.12065 -0.2794)
			(end 0.12065 -0.2794)
			(stroke
				(width 0.1)
				(type default)
			)
			(layer "F.Fab")
		)
		(fp_line
			(start -0.12065 0.2794)
			(end -0.12065 0.3048)
			(stroke
				(width 0.1)
				(type default)
			)
			(layer "F.Fab")
		)
		(fp_line
			(start -0.12065 0.3048)
			(end -0.67945 0.3048)
			(stroke
				(width 0.1)
				(type default)
			)
			(layer "F.Fab")
		)
		(fp_line
			(start 0.120396 0.2794)
			(end -0.12065 0.2794)
			(stroke
				(width 0.1)
				(type default)
			)
			(layer "F.Fab")
		)
		(fp_line
			(start 0.120396 0.3048)
			(end 0.120396 0.2794)
			(stroke
				(width 0.1)
				(type default)
			)
			(layer "F.Fab")
		)
		(fp_line
			(start 0.12065 -0.3048)
			(end 0.67945 -0.3048)
			(stroke
				(width 0.1)
				(type default)
			)
			(layer "F.Fab")
		)
		(fp_line
			(start 0.12065 -0.2794)
			(end 0.12065 -0.3048)
			(stroke
				(width 0.1)
				(type default)
			)
			(layer "F.Fab")
		)
		(fp_line
			(start 0.67945 -0.3048)
			(end 0.67945 0.3048)
			(stroke
				(width 0.1)
				(type default)
			)
			(layer "F.Fab")
		)
		(fp_line
			(start 0.67945 0.3048)
			(end 0.120396 0.3048)
			(stroke
				(width 0.1)
				(type default)
			)
			(layer "F.Fab")
		)
		(pad "1" smd circle
			(at -0.40005 0)
			(size 0 0)
			(layers "F.Cu" "F.Mask" "F.Paste")
			(net "PWRGD_P3V3_SSD3")
		)
		(pad "2" smd circle
			(at 0.40005 0)
			(size 0 0)
			(layers "F.Cu" "F.Mask" "F.Paste")
			(net "PWRGD_P3V3_SSD3_R")
		)
	)
	(footprint ""
		(layer "F.Cu")
		(at 458.219048 -254.344932 -90)
		(property "Reference" "C4398"
			(at 0 0 270)
			(layer "F.SilkS")
			(hide yes)
			(effects
				(font
					(size 1.27 1.27)
				)
			)
		)
		(property "Value" ""
			(at 0 0 270)
			(layer "F.Fab")
			(effects
				(font
					(size 1.27 1.27)
				)
			)
		)
		(duplicate_pad_numbers_are_jumpers no)
		(fp_line
			(start -1.524 0.762)
			(end -1.524 -0.762)
			(stroke
				(width 0.1524)
				(type default)
			)
			(layer "F.SilkS")
		)
		(fp_line
			(start 1.524 0.762)
			(end -1.524 0.762)
			(stroke
				(width 0.1524)
				(type default)
			)
			(layer "F.SilkS")
		)
		(fp_line
			(start -1.524 -0.762)
			(end 1.524 -0.762)
			(stroke
				(width 0.1524)
				(type default)
			)
			(layer "F.SilkS")
		)
		(fp_line
			(start 1.524 -0.762)
			(end 1.524 0.762)
			(stroke
				(width 0.1524)
				(type default)
			)
			(layer "F.SilkS")
		)
		(fp_line
			(start -1.1049 0.724916)
			(end 1.1049 0.724916)
			(stroke
				(width 0.1)
				(type default)
			)
			(layer "F.Fab")
		)
		(fp_line
			(start 1.1049 0.724916)
			(end 1.1049 -0.724916)
			(stroke
				(width 0.1)
				(type default)
			)
			(layer "F.Fab")
		)
		(fp_line
			(start -1.1049 -0.724916)
			(end -1.1049 0.724916)
			(stroke
				(width 0.1)
				(type default)
			)
			(layer "F.Fab")
		)
		(fp_line
			(start 1.1049 -0.724916)
			(end -1.1049 -0.724916)
			(stroke
				(width 0.1)
				(type default)
			)
			(layer "F.Fab")
		)
		(pad "1" smd rect
			(at -0.889 0 90)
			(size 1.016 1.27)
			(layers "F.Cu" "F.Mask" "F.Paste")
			(net "P1V25_SERDES_VDDPLL_PEX3_C4")
		)
		(pad "2" smd rect
			(at 0.889 0 90)
			(size 1.016 1.27)
			(layers "F.Cu" "F.Mask" "F.Paste")
			(net "GND")
		)
		(zone
			(layer "F.Cu")
			(hatch none 0.5)
			(connect_pads
				(clearance 0)
			)
			(min_thickness 0.25)
			(keepout
				(tracks not_allowed)
				(vias allowed)
				(pads allowed)
				(copperpour not_allowed)
				(footprints allowed)
			)
			(placement
				(enabled no)
				(sheetname "")
			)
			(fill
				(thermal_gap 0.5)
				(thermal_bridge_width 0.5)
				(island_removal_mode 0)
			)
			(polygon
				(pts
					(xy 458.943964 -254.675132) (xy 457.494132 -254.675132) (xy 457.494132 -254.014732) (xy 458.943964 -254.014732)
				)
			)
		)
	)
)
